(kicad_pcb
	(version 20241229)
	(generator "pcbnew")
	(generator_version "9.0")
	(general
		(thickness 1.711)
		(legacy_teardrops no)
	)
	(paper "A4")
	(title_block
		(title "Antmicro Baseboard for Jetson AGX Thor")
		(date "2026-02-18")
		(rev "1.1.0")
		(company "Antmicro Ltd")
		(comment 1 "www.antmicro.com")
		(comment 9 "footprints 330-333 of 1170")
	)
	(layers
		(0 "F.Cu" signal)
		(4 "In1.Cu" signal)
		(6 "In2.Cu" signal)
		(8 "In3.Cu" signal)
		(10 "In4.Cu" jumper)
		(12 "In5.Cu" signal)
		(14 "In6.Cu" signal)
		(16 "In7.Cu" signal)
		(18 "In8.Cu" signal)
		(2 "B.Cu" signal)
		(9 "F.Adhes" user "F.Adhesive")
		(11 "B.Adhes" user "B.Adhesive")
		(13 "F.Paste" user)
		(15 "B.Paste" user)
		(5 "F.SilkS" user "F.Silkscreen")
		(7 "B.SilkS" user "B.Silkscreen")
		(1 "F.Mask" user)
		(3 "B.Mask" user)
		(17 "Dwgs.User" user "User.Drawings")
		(19 "Cmts.User" user "User.Comments")
		(21 "Eco1.User" user "User.Eco1")
		(23 "Eco2.User" user "User.Eco2")
		(25 "Edge.Cuts" user)
		(27 "Margin" user)
		(31 "F.CrtYd" user "F.Courtyard")
		(29 "B.CrtYd" user "B.Courtyard")
		(35 "F.Fab" user)
		(33 "B.Fab" user)
	)
	(footprint "antmicro-footprints:C_0402_1005Metric"
		(layer "F.Cu")
		(at 207 76.2 90)
		(descr "Capacitor SMD 0402")
		(tags "capacitor SMD 0402")
		(property "Reference" "C143"
			(at 0.9 0.4 90)
			(layer "F.SilkS")
			(effects
				(font
					(size 0.7 0.7)
					(thickness 0.15)
				)
				(justify left bottom)
			)
		)
		(property "Value" "C_100n_0402"
			(at -1.022927 2.155213 90)
			(layer "F.Fab")
			(effects
				(font
					(size 0.7 0.7)
					(thickness 0.15)
				)
				(justify left bottom)
			)
		)
		(property "Datasheet" "https://www.murata.com/products/productdetail?partno=GRM155R61H104KE14%23"
			(at 0 0 90)
			(layer "F.Fab")
			(hide yes)
			(effects
				(font
					(size 1.27 1.27)
					(thickness 0.15)
				)
			)
		)
		(property "Description" "SMD Multilayer Ceramic Capacitor, 0.1 µF, 50 V, 0402 [1005 Metric], ± 10%, X5R, GRM Series"
			(at 0 0 90)
			(layer "F.Fab")
			(hide yes)
			(effects
				(font
					(size 1.27 1.27)
					(thickness 0.15)
				)
			)
		)
		(property "MPN" "GRM155R61H104KE14D"
			(at 0 0 90)
			(unlocked yes)
			(layer "F.Fab")
			(hide yes)
			(effects
				(font
					(size 1 1)
					(thickness 0.15)
				)
			)
		)
		(property "Manufacturer" "Murata"
			(at 0 0 90)
			(unlocked yes)
			(layer "F.Fab")
			(hide yes)
			(effects
				(font
					(size 1 1)
					(thickness 0.15)
				)
			)
		)
		(property "Val" "100n"
			(at 0 0 90)
			(unlocked yes)
			(layer "F.Fab")
			(hide yes)
			(effects
				(font
					(size 1 1)
					(thickness 0.15)
				)
			)
		)
		(property "License" "Apache-2.0"
			(at 0 0 90)
			(unlocked yes)
			(layer "F.Fab")
			(hide yes)
			(effects
				(font
					(size 1 1)
					(thickness 0.15)
				)
			)
		)
		(property "Author" "Antmicro"
			(at 0 0 90)
			(unlocked yes)
			(layer "F.Fab")
			(hide yes)
			(effects
				(font
					(size 1 1)
					(thickness 0.15)
				)
			)
		)
		(property "Voltage" "50V"
			(at 0 0 90)
			(unlocked yes)
			(layer "F.Fab")
			(hide yes)
			(effects
				(font
					(size 1 1)
					(thickness 0.15)
				)
			)
		)
		(property "Dielectric" "X5R"
			(at 0 0 90)
			(unlocked yes)
			(layer "F.Fab")
			(hide yes)
			(effects
				(font
					(size 1 1)
					(thickness 0.15)
				)
			)
		)
		(sheetname "/USB Debug, PD/")
		(sheetfile "usb_debug_pd.kicad_sch")
		(attr smd)
		(fp_rect
			(start -0.925 -0.47)
			(end 0.925 0.47)
			(stroke
				(width 0.05)
				(type default)
			)
			(fill no)
			(layer "F.CrtYd")
		)
		(fp_line
			(start 0.504 -0.25)
			(end 0.504 0.248)
			(stroke
				(width 0.15)
				(type solid)
			)
			(layer "F.Fab")
		)
		(fp_line
			(start -0.494 -0.25)
			(end 0.504 -0.25)
			(stroke
				(width 0.15)
				(type solid)
			)
			(layer "F.Fab")
		)
		(fp_line
			(start 0.504 0.248)
			(end -0.494 0.248)
			(stroke
				(width 0.15)
				(type solid)
			)
			(layer "F.Fab")
		)
		(fp_line
			(start -0.494 0.248)
			(end -0.494 -0.25)
			(stroke
				(width 0.15)
				(type solid)
			)
			(layer "F.Fab")
		)
		(fp_text user "${REFERENCE}"
			(at -0.939 4.599 90)
			(layer "F.Fab")
			(effects
				(font
					(size 0.7 0.7)
					(thickness 0.15)
				)
				(justify left bottom)
			)
		)
		(fp_text user "License: Apache-2.0"
			(at -0.939 5.799 90)
			(layer "F.Fab")
			(effects
				(font
					(size 0.7 0.7)
					(thickness 0.15)
				)
				(justify left bottom)
			)
		)
		(fp_text user "Author: Antmicro"
			(at -0.939 3.399 90)
			(layer "F.Fab")
			(effects
				(font
					(size 0.7 0.7)
					(thickness 0.15)
				)
				(justify left bottom)
			)
		)
		(pad "1" smd roundrect
			(at -0.48 0 90)
			(size 0.59 0.64)
			(layers "F.Cu" "F.Mask" "F.Paste")
			(roundrect_rratio 0.25)
			(net 525 "/Power/USBPD2_HV")
			(pintype "passive")
		)
		(pad "2" smd roundrect
			(at 0.48 0 90)
			(size 0.59 0.64)
			(layers "F.Cu" "F.Mask" "F.Paste")
			(roundrect_rratio 0.25)
			(net 1 "GND")
			(pintype "passive")
		)
	)
	(footprint "antmicro-footprints:C_0603_1608Metric_EIA"
		(layer "F.Cu")
		(at 186.94 127.3 -90)
		(descr "Capacitor SMD 0603, IPC-7351 Density Level A")
		(tags "Capacitor 0603")
		(property "Reference" "C76"
			(at 1.1 0.34 90)
			(layer "F.SilkS")
			(effects
				(font
					(size 0.7 0.7)
					(thickness 0.15)
				)
				(justify right top)
			)
		)
		(property "Value" "C_22u_16V_0603"
			(at -1.42757 1.770288 90)
			(layer "F.Fab")
			(effects
				(font
					(size 0.7 0.7)
					(thickness 0.15)
				)
				(justify right top)
			)
		)
		(property "Datasheet" "https://product.samsungsem.com/mlcc/CL10A226MO7JZN.do"
			(at 0 0 90)
			(layer "F.Fab")
			(hide yes)
			(effects
				(font
					(size 1.27 1.27)
					(thickness 0.15)
				)
			)
		)
		(property "Description" "SMD Multilayer Ceramic Capacitor"
			(at 0 0 90)
			(layer "F.Fab")
			(hide yes)
			(effects
				(font
					(size 1.27 1.27)
					(thickness 0.15)
				)
			)
		)
		(property "MPN" "CL10A226MO7JZNC"
			(at 0 0 90)
			(unlocked yes)
			(layer "F.Fab")
			(hide yes)
			(effects
				(font
					(size 1 1)
					(thickness 0.15)
				)
			)
		)
		(property "Manufacturer" "Samsung Electro-Mechanics"
			(at 0 0 90)
			(unlocked yes)
			(layer "F.Fab")
			(hide yes)
			(effects
				(font
					(size 1 1)
					(thickness 0.15)
				)
			)
		)
		(property "License" "Apache-2.0"
			(at 0 0 90)
			(unlocked yes)
			(layer "F.Fab")
			(hide yes)
			(effects
				(font
					(size 1 1)
					(thickness 0.15)
				)
			)
		)
		(property "Author" "Antmicro"
			(at 0 0 90)
			(unlocked yes)
			(layer "F.Fab")
			(hide yes)
			(effects
				(font
					(size 1 1)
					(thickness 0.15)
				)
			)
		)
		(property "Val" "22u"
			(at 0 0 90)
			(unlocked yes)
			(layer "F.Fab")
			(hide yes)
			(effects
				(font
					(size 1 1)
					(thickness 0.15)
				)
			)
		)
		(property "Voltage" "16V"
			(at 0 0 90)
			(unlocked yes)
			(layer "F.Fab")
			(hide yes)
			(effects
				(font
					(size 1 1)
					(thickness 0.15)
				)
			)
		)
		(property "Dielectric" ""
			(at 0 0 90)
			(unlocked yes)
			(layer "F.Fab")
			(hide yes)
			(effects
				(font
					(size 1 1)
					(thickness 0.15)
				)
			)
		)
		(property "Public" "False"
			(at 0 0 90)
			(unlocked yes)
			(layer "F.Fab")
			(hide yes)
			(effects
				(font
					(size 1 1)
					(thickness 0.15)
				)
			)
		)
		(component_classes
			(class "DCDC_1V15")
		)
		(sheetname "/DCDC/")
		(sheetfile "dcdc.kicad_sch")
		(attr smd)
		(fp_line
			(start -0.15 0.55)
			(end 0.15 0.55)
			(stroke
				(width 0.15)
				(type solid)
			)
			(layer "F.SilkS")
		)
		(fp_line
			(start -0.15 -0.55)
			(end 0.15 -0.55)
			(stroke
				(width 0.15)
				(type solid)
			)
			(layer "F.SilkS")
		)
		(fp_rect
			(start -1.25 -0.65)
			(end 1.25 0.65)
			(stroke
				(width 0.05)
				(type solid)
			)
			(fill no)
			(layer "F.CrtYd")
		)
		(fp_rect
			(start -0.8 -0.45)
			(end 0.8 0.45)
			(stroke
				(width 0.15)
				(type solid)
			)
			(fill no)
			(layer "F.Fab")
		)
		(fp_text user "License: Apache-2.0"
			(at -1.682 5.895 90)
			(layer "F.Fab")
			(effects
				(font
					(size 0.7 0.7)
					(thickness 0.15)
				)
				(justify right top)
			)
		)
		(fp_text user "Author: Antmicro"
			(at -1.682 4.894 90)
			(layer "F.Fab")
			(effects
				(font
					(size 0.7 0.7)
					(thickness 0.15)
				)
				(justify right top)
			)
		)
		(fp_text user "${REFERENCE}"
			(at -1.682 3.895 90)
			(layer "F.Fab")
			(effects
				(font
					(size 0.7 0.7)
					(thickness 0.15)
				)
				(justify right top)
			)
		)
		(pad "1" smd roundrect
			(at -0.7 0 270)
			(size 0.8 1.1)
			(layers "F.Cu" "F.Mask" "F.Paste")
			(roundrect_rratio 0.2)
			(net 1 "GND")
			(pintype "passive")
		)
		(pad "2" smd roundrect
			(at 0.7 0 270)
			(size 0.8 1.1)
			(layers "F.Cu" "F.Mask" "F.Paste")
			(roundrect_rratio 0.2)
			(net 5 "+5V")
			(pintype "passive")
		)
	)
	(footprint "antmicro-footprints:R_0402_1005Metric"
		(layer "F.Cu")
		(at 90.03 148.199999)
		(descr "Resistor SMD 0402")
		(tags "resistor SMD 0402")
		(property "Reference" "R190"
			(at -1.83 2.800001 0)
			(layer "F.SilkS")
			(effects
				(font
					(size 0.7 0.7)
					(thickness 0.15)
				)
				(justify left bottom)
			)
		)
		(property "Value" "R_33R_0402"
			(at -1.011843 1.772046 0)
			(layer "F.Fab")
			(effects
				(font
					(size 0.7 0.7)
					(thickness 0.15)
				)
				(justify left bottom)
			)
		)
		(property "Datasheet" "https://www.bourns.com/docs/product-datasheets/cr.pdf"
			(at 0 0 0)
			(layer "F.Fab")
			(hide yes)
			(effects
				(font
					(size 1.27 1.27)
					(thickness 0.15)
				)
			)
		)
		(property "Description" "SMD Chip Resistor, 33 ohm, ± 1%, 62.5 mW, 0402 [1005 Metric], Thick Film, General Purpose"
			(at 0 0 0)
			(layer "F.Fab")
			(hide yes)
			(effects
				(font
					(size 1.27 1.27)
					(thickness 0.15)
				)
			)
		)
		(property "MPN" "CR0402-FX-33R0GLF"
			(at 0 0 0)
			(unlocked yes)
			(layer "F.Fab")
			(hide yes)
			(effects
				(font
					(size 1 1)
					(thickness 0.15)
				)
			)
		)
		(property "Manufacturer" "Bourns"
			(at 0 0 0)
			(unlocked yes)
			(layer "F.Fab")
			(hide yes)
			(effects
				(font
					(size 1 1)
					(thickness 0.15)
				)
			)
		)
		(property "License" "Apache-2.0"
			(at 0 0 0)
			(unlocked yes)
			(layer "F.Fab")
			(hide yes)
			(effects
				(font
					(size 1 1)
					(thickness 0.15)
				)
			)
		)
		(property "Author" "Antmicro"
			(at 0 0 0)
			(unlocked yes)
			(layer "F.Fab")
			(hide yes)
			(effects
				(font
					(size 1 1)
					(thickness 0.15)
				)
			)
		)
		(property "Val" "33R"
			(at 0 0 0)
			(unlocked yes)
			(layer "F.Fab")
			(hide yes)
			(effects
				(font
					(size 1 1)
					(thickness 0.15)
				)
			)
		)
		(property "Tolerance" "1%"
			(at 0 0 0)
			(unlocked yes)
			(layer "F.Fab")
			(hide yes)
			(effects
				(font
					(size 1 1)
					(thickness 0.15)
				)
			)
		)
		(sheetname "/SoM_IO2/")
		(sheetfile "som_io2.kicad_sch")
		(attr smd)
		(fp_poly
			(pts
				(xy -0.925 -0.47) (xy -0.925 0.47) (xy 0.925 0.47) (xy 0.925 -0.47)
			)
			(stroke
				(width 0.05)
				(type default)
			)
			(fill no)
			(layer "F.CrtYd")
		)
		(fp_poly
			(pts
				(xy -0.5 -0.25) (xy -0.5 0.25) (xy 0.5 0.25) (xy 0.5 -0.25)
			)
			(stroke
				(width 0.15)
				(type solid)
			)
			(fill no)
			(layer "F.Fab")
		)
		(fp_text user "${REFERENCE}"
			(at -0.95 3.168 0)
			(layer "F.Fab")
			(effects
				(font
					(size 0.7 0.7)
					(thickness 0.15)
				)
				(justify left bottom)
			)
		)
		(fp_text user "License: Apache-2.0"
			(at -0.949999 5.169 0)
			(layer "F.Fab")
			(effects
				(font
					(size 0.7 0.7)
					(thickness 0.15)
				)
				(justify left bottom)
			)
		)
		(fp_text user "Author: Antmicro"
			(at -0.95 4.169 0)
			(layer "F.Fab")
			(effects
				(font
					(size 0.7 0.7)
					(thickness 0.15)
				)
				(justify left bottom)
			)
		)
		(pad "1" smd roundrect
			(at -0.48 0)
			(size 0.59 0.64)
			(layers "F.Cu" "F.Mask" "F.Paste")
			(roundrect_rratio 0.25)
			(net 1001 "/SoM_IO2/C2_CLK-")
			(pintype "passive")
		)
		(pad "2" smd roundrect
			(at 0.48 0)
			(size 0.59 0.64)
			(layers "F.Cu" "F.Mask" "F.Paste")
			(roundrect_rratio 0.25)
			(net 1002 "/SoM_IO2/C2_REFCLK-")
			(pintype "passive")
		)
	)
	(footprint "antmicro-footprints:R_0402_1005Metric"
		(layer "F.Cu")
		(at 141.7 111.72 -90)
		(descr "Resistor SMD 0402")
		(tags "resistor SMD 0402")
		(property "Reference" "R406"
			(at 0.78 0.4 90)
			(layer "F.SilkS")
			(effects
				(font
					(size 0.7 0.7)
					(thickness 0.15)
				)
				(justify right top)
			)
		)
		(property "Value" "R_0R_0402"
			(at -1.011843 1.772047 90)
			(layer "F.Fab")
			(effects
				(font
					(size 0.7 0.7)
					(thickness 0.15)
				)
				(justify right top)
			)
		)
		(property "Datasheet" "https://industrial.panasonic.com/cdbs/www-data/pdf/RDA0000/AOA0000C301.pdf"
			(at 0 0 90)
			(layer "F.Fab")
			(hide yes)
			(effects
				(font
					(size 1.27 1.27)
					(thickness 0.15)
				)
			)
		)
		(property "Description" "SMD Chip Resistor, Jumper, 0 ohm, 100 mW, 0402 [1005 Metric], Thick Film, General Purpose"
			(at 0 0 90)
			(layer "F.Fab")
			(hide yes)
			(effects
				(font
					(size 1.27 1.27)
					(thickness 0.15)
				)
			)
		)
		(property "MPN" "ERJ2GE0R00X"
			(at 0 0 270)
			(unlocked yes)
			(layer "F.Fab")
			(hide yes)
			(effects
				(font
					(size 1 1)
					(thickness 0.15)
				)
			)
		)
		(property "Manufacturer" "Panasonic"
			(at 0 0 270)
			(unlocked yes)
			(layer "F.Fab")
			(hide yes)
			(effects
				(font
					(size 1 1)
					(thickness 0.15)
				)
			)
		)
		(property "License" "Apache-2.0"
			(at 0 0 270)
			(unlocked yes)
			(layer "F.Fab")
			(hide yes)
			(effects
				(font
					(size 1 1)
					(thickness 0.15)
				)
			)
		)
		(property "Author" "Antmicro"
			(at 0 0 270)
			(unlocked yes)
			(layer "F.Fab")
			(hide yes)
			(effects
				(font
					(size 1 1)
					(thickness 0.15)
				)
			)
		)
		(property "Val" "0R"
			(at 0 0 270)
			(unlocked yes)
			(layer "F.Fab")
			(hide yes)
			(effects
				(font
					(size 1 1)
					(thickness 0.15)
				)
			)
		)
		(property "Tolerance" "~"
			(at 0 0 270)
			(unlocked yes)
			(layer "F.Fab")
			(hide yes)
			(effects
				(font
					(size 1 1)
					(thickness 0.15)
				)
			)
		)
		(property "Current" "1A"
			(at 0 0 270)
			(unlocked yes)
			(layer "F.Fab")
			(hide yes)
			(effects
				(font
					(size 1 1)
					(thickness 0.15)
				)
			)
		)
		(sheetname "/Peripherals/")
		(sheetfile "peripherals.kicad_sch")
		(attr smd)
		(fp_rect
			(start -0.925 -0.47)
			(end 0.925 0.47)
			(stroke
				(width 0.05)
				(type default)
			)
			(fill no)
			(layer "F.CrtYd")
		)
		(fp_rect
			(start -0.5 -0.25)
			(end 0.5 0.25)
			(stroke
				(width 0.15)
				(type solid)
			)
			(fill no)
			(layer "F.Fab")
		)
		(fp_text user "Author: Antmicro"
			(at -0.95 4.169 90)
			(layer "F.Fab")
			(effects
				(font
					(size 0.7 0.7)
					(thickness 0.15)
				)
				(justify right top)
			)
		)
		(fp_text user "${REFERENCE}"
			(at -0.95 3.168 90)
			(layer "F.Fab")
			(effects
				(font
					(size 0.7 0.7)
					(thickness 0.15)
				)
				(justify right top)
			)
		)
		(fp_text user "License: Apache-2.0"
			(at -0.95 5.169 90)
			(layer "F.Fab")
			(effects
				(font
					(size 0.7 0.7)
					(thickness 0.15)
				)
				(justify right top)
			)
		)
		(pad "1" smd roundrect
			(at -0.48 0 270)
			(size 0.59 0.64)
			(layers "F.Cu" "F.Mask" "F.Paste")
			(roundrect_rratio 0.25)
			(net 1319 "/Peripherals/GPIOEX_P0_7")
			(pintype "passive")
		)
		(pad "2" smd roundrect
			(at 0.48 0 270)
			(size 0.59 0.64)
			(layers "F.Cu" "F.Mask" "F.Paste")
			(roundrect_rratio 0.25)
			(net 1378 "Net-(R406-Pad2)")
			(pintype "passive")
		)
	)
)
